(kicad_pcb
	(version 20260206)
	(generator "pcbnew")
	(generator_version "10.0")
	(general
		(thickness 1.6)
		(legacy_teardrops no)
	)
	(paper "A4")
	(title_block
		(title "04192023_DAF0TMB3IC0_F0TG_MB_C_brd_V02_OCP.brd")
		(comment 1 "Grand Teton / footprints 3432-3438 of 8354")
	)
	(layers
		(0 "F.Cu" signal "TOP")
		(4 "In1.Cu" signal "GND")
		(6 "In2.Cu" signal "IN1")
		(8 "In3.Cu" signal "GND1")
		(10 "In4.Cu" signal "IN2")
		(12 "In5.Cu" signal "GND2")
		(14 "In6.Cu" signal "IN3")
		(16 "In7.Cu" signal "GND3")
		(18 "In8.Cu" signal "VCC")
		(20 "In9.Cu" signal "VCC1")
		(22 "In10.Cu" signal "GND4")
		(24 "In11.Cu" signal "IN4")
		(26 "In12.Cu" signal "GND5")
		(28 "In13.Cu" signal "IN5")
		(30 "In14.Cu" signal "GND6")
		(32 "In15.Cu" signal "IN6")
		(34 "In16.Cu" signal "GND7")
		(2 "B.Cu" signal "BOTTOM")
		(9 "F.Adhes" user "F.Adhesive")
		(11 "B.Adhes" user "B.Adhesive")
		(13 "F.Paste" user "Package Geometry/Pastemask Top")
		(15 "B.Paste" user "Package Geometry/Pastemask Bottom")
		(5 "F.SilkS" user "Ref Des/Silkscreen Top")
		(7 "B.SilkS" user "Ref Des/Silkscreen Bottom")
		(1 "F.Mask" user "Board Geometry/Soldermask Top")
		(3 "B.Mask" user "Board Geometry/Soldermask Bottom")
		(17 "Dwgs.User" user "User.Drawings")
		(19 "Cmts.User" user "User.Comments")
		(21 "Eco1.User" user "User.Eco1")
		(23 "Eco2.User" user "User.Eco2")
		(25 "Edge.Cuts" user "Board Geometry/Outline")
		(27 "Margin" user)
		(31 "F.CrtYd" user "Package Geometry/Place Bound Top")
		(29 "B.CrtYd" user "Package Geometry/Place Bound Bottom")
		(35 "F.Fab" user "Ref Des/Assembly Top")
		(33 "B.Fab" user "Ref Des/Assembly Bottom")
	)
	(footprint ""
		(layer "F.Cu")
		(at 98.550222 -36.305998)
		(property "Reference" "C1824"
			(at 0 0 0)
			(layer "F.SilkS")
			(hide yes)
			(effects
				(font
					(size 1.27 1.27)
				)
			)
		)
		(property "Value" ""
			(at 0 0 0)
			(layer "F.Fab")
			(effects
				(font
					(size 1.27 1.27)
				)
			)
		)
		(duplicate_pad_numbers_are_jumpers no)
		(fp_line
			(start -0.7874 -0.4064)
			(end 0.7874 -0.4064)
			(stroke
				(width 0.1524)
				(type default)
			)
			(layer "F.SilkS")
		)
		(fp_line
			(start -0.7874 0.4064)
			(end -0.7874 -0.4064)
			(stroke
				(width 0.1524)
				(type default)
			)
			(layer "F.SilkS")
		)
		(fp_line
			(start 0.7874 -0.4064)
			(end 0.7874 0.4064)
			(stroke
				(width 0.1524)
				(type default)
			)
			(layer "F.SilkS")
		)
		(fp_line
			(start 0.7874 0.4064)
			(end -0.7874 0.4064)
			(stroke
				(width 0.1524)
				(type default)
			)
			(layer "F.SilkS")
		)
		(fp_line
			(start -0.67945 -0.305054)
			(end -0.12065 -0.305054)
			(stroke
				(width 0.1)
				(type default)
			)
			(layer "F.Fab")
		)
		(fp_line
			(start -0.67945 0.3048)
			(end -0.67945 -0.305054)
			(stroke
				(width 0.1)
				(type default)
			)
			(layer "F.Fab")
		)
		(fp_line
			(start -0.12065 -0.305054)
			(end -0.12065 -0.2794)
			(stroke
				(width 0.1)
				(type default)
			)
			(layer "F.Fab")
		)
		(fp_line
			(start -0.12065 -0.2794)
			(end 0.12065 -0.2794)
			(stroke
				(width 0.1)
				(type default)
			)
			(layer "F.Fab")
		)
		(fp_line
			(start -0.12065 0.2794)
			(end -0.12065 0.3048)
			(stroke
				(width 0.1)
				(type default)
			)
			(layer "F.Fab")
		)
		(fp_line
			(start -0.12065 0.3048)
			(end -0.67945 0.3048)
			(stroke
				(width 0.1)
				(type default)
			)
			(layer "F.Fab")
		)
		(fp_line
			(start 0.120396 0.2794)
			(end -0.12065 0.2794)
			(stroke
				(width 0.1)
				(type default)
			)
			(layer "F.Fab")
		)
		(fp_line
			(start 0.120396 0.3048)
			(end 0.120396 0.2794)
			(stroke
				(width 0.1)
				(type default)
			)
			(layer "F.Fab")
		)
		(fp_line
			(start 0.12065 -0.3048)
			(end 0.67945 -0.3048)
			(stroke
				(width 0.1)
				(type default)
			)
			(layer "F.Fab")
		)
		(fp_line
			(start 0.12065 -0.2794)
			(end 0.12065 -0.3048)
			(stroke
				(width 0.1)
				(type default)
			)
			(layer "F.Fab")
		)
		(fp_line
			(start 0.67945 -0.3048)
			(end 0.67945 0.3048)
			(stroke
				(width 0.1)
				(type default)
			)
			(layer "F.Fab")
		)
		(fp_line
			(start 0.67945 0.3048)
			(end 0.120396 0.3048)
			(stroke
				(width 0.1)
				(type default)
			)
			(layer "F.Fab")
		)
		(pad "1" smd circle
			(at -0.40005 0)
			(size 0 0)
			(layers "F.Cu" "F.Mask" "F.Paste")
			(net "P3V3_AUX")
		)
		(pad "2" smd circle
			(at 0.40005 0)
			(size 0 0)
			(layers "F.Cu" "F.Mask" "F.Paste")
			(net "GND")
		)
	)
	(footprint ""
		(layer "F.Cu")
		(at 178.71694 -398.404842 180)
		(property "Reference" "PR1133"
			(at 0 0 180)
			(layer "F.SilkS")
			(hide yes)
			(effects
				(font
					(size 1.27 1.27)
				)
			)
		)
		(property "Value" ""
			(at 0 0 180)
			(layer "F.Fab")
			(effects
				(font
					(size 1.27 1.27)
				)
			)
		)
		(duplicate_pad_numbers_are_jumpers no)
		(fp_line
			(start 0.7874 0.4064)
			(end -0.7874 0.4064)
			(stroke
				(width 0.1524)
				(type default)
			)
			(layer "F.SilkS")
		)
		(fp_line
			(start 0.7874 -0.4064)
			(end 0.7874 0.4064)
			(stroke
				(width 0.1524)
				(type default)
			)
			(layer "F.SilkS")
		)
		(fp_line
			(start -0.7874 0.4064)
			(end -0.7874 -0.4064)
			(stroke
				(width 0.1524)
				(type default)
			)
			(layer "F.SilkS")
		)
		(fp_line
			(start -0.7874 -0.4064)
			(end 0.7874 -0.4064)
			(stroke
				(width 0.1524)
				(type default)
			)
			(layer "F.SilkS")
		)
		(fp_line
			(start 0.67945 0.3048)
			(end 0.120396 0.3048)
			(stroke
				(width 0.1)
				(type default)
			)
			(layer "F.Fab")
		)
		(fp_line
			(start 0.67945 -0.3048)
			(end 0.67945 0.3048)
			(stroke
				(width 0.1)
				(type default)
			)
			(layer "F.Fab")
		)
		(fp_line
			(start 0.12065 -0.2794)
			(end 0.12065 -0.3048)
			(stroke
				(width 0.1)
				(type default)
			)
			(layer "F.Fab")
		)
		(fp_line
			(start 0.12065 -0.3048)
			(end 0.67945 -0.3048)
			(stroke
				(width 0.1)
				(type default)
			)
			(layer "F.Fab")
		)
		(fp_line
			(start 0.120396 0.3048)
			(end 0.120396 0.2794)
			(stroke
				(width 0.1)
				(type default)
			)
			(layer "F.Fab")
		)
		(fp_line
			(start 0.120396 0.2794)
			(end -0.12065 0.2794)
			(stroke
				(width 0.1)
				(type default)
			)
			(layer "F.Fab")
		)
		(fp_line
			(start -0.12065 0.3048)
			(end -0.67945 0.3048)
			(stroke
				(width 0.1)
				(type default)
			)
			(layer "F.Fab")
		)
		(fp_line
			(start -0.12065 0.2794)
			(end -0.12065 0.3048)
			(stroke
				(width 0.1)
				(type default)
			)
			(layer "F.Fab")
		)
		(fp_line
			(start -0.12065 -0.2794)
			(end 0.12065 -0.2794)
			(stroke
				(width 0.1)
				(type default)
			)
			(layer "F.Fab")
		)
		(fp_line
			(start -0.12065 -0.305054)
			(end -0.12065 -0.2794)
			(stroke
				(width 0.1)
				(type default)
			)
			(layer "F.Fab")
		)
		(fp_line
			(start -0.67945 0.3048)
			(end -0.67945 -0.305054)
			(stroke
				(width 0.1)
				(type default)
			)
			(layer "F.Fab")
		)
		(fp_line
			(start -0.67945 -0.305054)
			(end -0.12065 -0.305054)
			(stroke
				(width 0.1)
				(type default)
			)
			(layer "F.Fab")
		)
		(pad "1" smd circle
			(at -0.40005 0 180)
			(size 0 0)
			(layers "F.Cu" "F.Mask" "F.Paste")
			(net "HSC_IMON")
		)
		(pad "2" smd circle
			(at 0.40005 0 180)
			(size 0 0)
			(layers "F.Cu" "F.Mask" "F.Paste")
			(net "AGND_HSC")
		)
	)
	(footprint ""
		(layer "F.Cu")
		(at 386.211826 -58.7375 180)
		(property "Reference" "R1628"
			(at 0 0 180)
			(layer "F.SilkS")
			(hide yes)
			(effects
				(font
					(size 1.27 1.27)
				)
			)
		)
		(property "Value" ""
			(at 0 0 180)
			(layer "F.Fab")
			(effects
				(font
					(size 1.27 1.27)
				)
			)
		)
		(duplicate_pad_numbers_are_jumpers no)
		(fp_line
			(start 0.7874 0.4064)
			(end -0.7874 0.4064)
			(stroke
				(width 0.1524)
				(type default)
			)
			(layer "F.SilkS")
		)
		(fp_line
			(start 0.7874 -0.4064)
			(end 0.7874 0.4064)
			(stroke
				(width 0.1524)
				(type default)
			)
			(layer "F.SilkS")
		)
		(fp_line
			(start -0.7874 0.4064)
			(end -0.7874 -0.4064)
			(stroke
				(width 0.1524)
				(type default)
			)
			(layer "F.SilkS")
		)
		(fp_line
			(start -0.7874 -0.4064)
			(end 0.7874 -0.4064)
			(stroke
				(width 0.1524)
				(type default)
			)
			(layer "F.SilkS")
		)
		(fp_line
			(start 0.67945 0.3048)
			(end 0.120396 0.3048)
			(stroke
				(width 0.1)
				(type default)
			)
			(layer "F.Fab")
		)
		(fp_line
			(start 0.67945 -0.3048)
			(end 0.67945 0.3048)
			(stroke
				(width 0.1)
				(type default)
			)
			(layer "F.Fab")
		)
		(fp_line
			(start 0.12065 -0.2794)
			(end 0.12065 -0.3048)
			(stroke
				(width 0.1)
				(type default)
			)
			(layer "F.Fab")
		)
		(fp_line
			(start 0.12065 -0.3048)
			(end 0.67945 -0.3048)
			(stroke
				(width 0.1)
				(type default)
			)
			(layer "F.Fab")
		)
		(fp_line
			(start 0.120396 0.3048)
			(end 0.120396 0.2794)
			(stroke
				(width 0.1)
				(type default)
			)
			(layer "F.Fab")
		)
		(fp_line
			(start 0.120396 0.2794)
			(end -0.12065 0.2794)
			(stroke
				(width 0.1)
				(type default)
			)
			(layer "F.Fab")
		)
		(fp_line
			(start -0.12065 0.3048)
			(end -0.67945 0.3048)
			(stroke
				(width 0.1)
				(type default)
			)
			(layer "F.Fab")
		)
		(fp_line
			(start -0.12065 0.2794)
			(end -0.12065 0.3048)
			(stroke
				(width 0.1)
				(type default)
			)
			(layer "F.Fab")
		)
		(fp_line
			(start -0.12065 -0.2794)
			(end 0.12065 -0.2794)
			(stroke
				(width 0.1)
				(type default)
			)
			(layer "F.Fab")
		)
		(fp_line
			(start -0.12065 -0.305054)
			(end -0.12065 -0.2794)
			(stroke
				(width 0.1)
				(type default)
			)
			(layer "F.Fab")
		)
		(fp_line
			(start -0.67945 0.3048)
			(end -0.67945 -0.305054)
			(stroke
				(width 0.1)
				(type default)
			)
			(layer "F.Fab")
		)
		(fp_line
			(start -0.67945 -0.305054)
			(end -0.12065 -0.305054)
			(stroke
				(width 0.1)
				(type default)
			)
			(layer "F.Fab")
		)
		(pad "1" smd circle
			(at -0.40005 0 180)
			(size 0 0)
			(layers "F.Cu" "F.Mask" "F.Paste")
			(net "PVDD18_S5_P0")
		)
		(pad "2" smd circle
			(at 0.40005 0 180)
			(size 0 0)
			(layers "F.Cu" "F.Mask" "F.Paste")
			(net "HDT_HDR_TDO")
		)
	)
	(footprint ""
		(layer "F.Cu")
		(at 191.135 -137.632948 90)
		(property "Reference" "R937"
			(at 0 0 90)
			(layer "F.SilkS")
			(hide yes)
			(effects
				(font
					(size 1.27 1.27)
				)
			)
		)
		(property "Value" ""
			(at 0 0 90)
			(layer "F.Fab")
			(effects
				(font
					(size 1.27 1.27)
				)
			)
		)
		(duplicate_pad_numbers_are_jumpers no)
		(fp_line
			(start 0.7874 -0.4064)
			(end 0.7874 0.4064)
			(stroke
				(width 0.1524)
				(type default)
			)
			(layer "F.SilkS")
		)
		(fp_line
			(start -0.7874 -0.4064)
			(end 0.7874 -0.4064)
			(stroke
				(width 0.1524)
				(type default)
			)
			(layer "F.SilkS")
		)
		(fp_line
			(start 0.7874 0.4064)
			(end -0.7874 0.4064)
			(stroke
				(width 0.1524)
				(type default)
			)
			(layer "F.SilkS")
		)
		(fp_line
			(start -0.7874 0.4064)
			(end -0.7874 -0.4064)
			(stroke
				(width 0.1524)
				(type default)
			)
			(layer "F.SilkS")
		)
		(fp_line
			(start -0.12065 -0.305054)
			(end -0.12065 -0.2794)
			(stroke
				(width 0.1)
				(type default)
			)
			(layer "F.Fab")
		)
		(fp_line
			(start -0.67945 -0.305054)
			(end -0.12065 -0.305054)
			(stroke
				(width 0.1)
				(type default)
			)
			(layer "F.Fab")
		)
		(fp_line
			(start 0.67945 -0.3048)
			(end 0.67945 0.3048)
			(stroke
				(width 0.1)
				(type default)
			)
			(layer "F.Fab")
		)
		(fp_line
			(start 0.12065 -0.3048)
			(end 0.67945 -0.3048)
			(stroke
				(width 0.1)
				(type default)
			)
			(layer "F.Fab")
		)
		(fp_line
			(start 0.12065 -0.2794)
			(end 0.12065 -0.3048)
			(stroke
				(width 0.1)
				(type default)
			)
			(layer "F.Fab")
		)
		(fp_line
			(start -0.12065 -0.2794)
			(end 0.12065 -0.2794)
			(stroke
				(width 0.1)
				(type default)
			)
			(layer "F.Fab")
		)
		(fp_line
			(start 0.120396 0.2794)
			(end -0.12065 0.2794)
			(stroke
				(width 0.1)
				(type default)
			)
			(layer "F.Fab")
		)
		(fp_line
			(start -0.12065 0.2794)
			(end -0.12065 0.3048)
			(stroke
				(width 0.1)
				(type default)
			)
			(layer "F.Fab")
		)
		(fp_line
			(start 0.67945 0.3048)
			(end 0.120396 0.3048)
			(stroke
				(width 0.1)
				(type default)
			)
			(layer "F.Fab")
		)
		(fp_line
			(start 0.120396 0.3048)
			(end 0.120396 0.2794)
			(stroke
				(width 0.1)
				(type default)
			)
			(layer "F.Fab")
		)
		(fp_line
			(start -0.12065 0.3048)
			(end -0.67945 0.3048)
			(stroke
				(width 0.1)
				(type default)
			)
			(layer "F.Fab")
		)
		(fp_line
			(start -0.67945 0.3048)
			(end -0.67945 -0.305054)
			(stroke
				(width 0.1)
				(type default)
			)
			(layer "F.Fab")
		)
		(pad "1" smd circle
			(at -0.40005 0 90)
			(size 0 0)
			(layers "F.Cu" "F.Mask" "F.Paste")
			(net "FM_BIOS_POST_CMPLT_BUF_R_N")
		)
		(pad "2" smd circle
			(at 0.40005 0 90)
			(size 0 0)
			(layers "F.Cu" "F.Mask" "F.Paste")
			(net "FM_BIOS_POST_CMPLT_BUF_N")
		)
	)
	(footprint ""
		(layer "F.Cu")
		(at 297.486324 -117.942614 180)
		(property "Reference" "R3396"
			(at 0 0 180)
			(layer "F.SilkS")
			(hide yes)
			(effects
				(font
					(size 1.27 1.27)
				)
			)
		)
		(property "Value" ""
			(at 0 0 180)
			(layer "F.Fab")
			(effects
				(font
					(size 1.27 1.27)
				)
			)
		)
		(duplicate_pad_numbers_are_jumpers no)
		(fp_line
			(start 0.7874 0.4064)
			(end -0.7874 0.4064)
			(stroke
				(width 0.1524)
				(type default)
			)
			(layer "F.SilkS")
		)
		(fp_line
			(start 0.7874 -0.4064)
			(end 0.7874 0.4064)
			(stroke
				(width 0.1524)
				(type default)
			)
			(layer "F.SilkS")
		)
		(fp_line
			(start -0.7874 0.4064)
			(end -0.7874 -0.4064)
			(stroke
				(width 0.1524)
				(type default)
			)
			(layer "F.SilkS")
		)
		(fp_line
			(start -0.7874 -0.4064)
			(end 0.7874 -0.4064)
			(stroke
				(width 0.1524)
				(type default)
			)
			(layer "F.SilkS")
		)
		(fp_line
			(start 0.67945 0.3048)
			(end 0.120396 0.3048)
			(stroke
				(width 0.1)
				(type default)
			)
			(layer "F.Fab")
		)
		(fp_line
			(start 0.67945 -0.3048)
			(end 0.67945 0.3048)
			(stroke
				(width 0.1)
				(type default)
			)
			(layer "F.Fab")
		)
		(fp_line
			(start 0.12065 -0.2794)
			(end 0.12065 -0.3048)
			(stroke
				(width 0.1)
				(type default)
			)
			(layer "F.Fab")
		)
		(fp_line
			(start 0.12065 -0.3048)
			(end 0.67945 -0.3048)
			(stroke
				(width 0.1)
				(type default)
			)
			(layer "F.Fab")
		)
		(fp_line
			(start 0.120396 0.3048)
			(end 0.120396 0.2794)
			(stroke
				(width 0.1)
				(type default)
			)
			(layer "F.Fab")
		)
		(fp_line
			(start 0.120396 0.2794)
			(end -0.12065 0.2794)
			(stroke
				(width 0.1)
				(type default)
			)
			(layer "F.Fab")
		)
		(fp_line
			(start -0.12065 0.3048)
			(end -0.67945 0.3048)
			(stroke
				(width 0.1)
				(type default)
			)
			(layer "F.Fab")
		)
		(fp_line
			(start -0.12065 0.2794)
			(end -0.12065 0.3048)
			(stroke
				(width 0.1)
				(type default)
			)
			(layer "F.Fab")
		)
		(fp_line
			(start -0.12065 -0.2794)
			(end 0.12065 -0.2794)
			(stroke
				(width 0.1)
				(type default)
			)
			(layer "F.Fab")
		)
		(fp_line
			(start -0.12065 -0.305054)
			(end -0.12065 -0.2794)
			(stroke
				(width 0.1)
				(type default)
			)
			(layer "F.Fab")
		)
		(fp_line
			(start -0.67945 0.3048)
			(end -0.67945 -0.305054)
			(stroke
				(width 0.1)
				(type default)
			)
			(layer "F.Fab")
		)
		(fp_line
			(start -0.67945 -0.305054)
			(end -0.12065 -0.305054)
			(stroke
				(width 0.1)
				(type default)
			)
			(layer "F.Fab")
		)
		(pad "1" smd circle
			(at -0.40005 0 180)
			(size 0 0)
			(layers "F.Cu" "F.Mask" "F.Paste")
			(net "P3V3_AUX")
		)
		(pad "2" smd circle
			(at 0.40005 0 180)
			(size 0 0)
			(layers "F.Cu" "F.Mask" "F.Paste")
			(net "SMB_INA230_3V3AUX_SDA")
		)
	)
	(footprint ""
		(layer "F.Cu")
		(at 366.089692 -381.41783 -90)
		(property "Reference" "C897"
			(at 0 0 270)
			(layer "F.SilkS")
			(hide yes)
			(effects
				(font
					(size 1.27 1.27)
				)
			)
		)
		(property "Value" ""
			(at 0 0 270)
			(layer "F.Fab")
			(effects
				(font
					(size 1.27 1.27)
				)
			)
		)
		(duplicate_pad_numbers_are_jumpers no)
		(fp_line
			(start -0.299974 0.150114)
			(end -0.299974 -0.150114)
			(stroke
				(width 0.1)
				(type default)
			)
			(layer "F.Fab")
		)
		(fp_line
			(start 0.299974 0.150114)
			(end -0.299974 0.150114)
			(stroke
				(width 0.1)
				(type default)
			)
			(layer "F.Fab")
		)
		(fp_line
			(start -0.299974 -0.150114)
			(end 0.299974 -0.150114)
			(stroke
				(width 0.1)
				(type default)
			)
			(layer "F.Fab")
		)
		(fp_line
			(start 0.299974 -0.150114)
			(end 0.299974 0.150114)
			(stroke
				(width 0.1)
				(type default)
			)
			(layer "F.Fab")
		)
		(pad "1" smd rect
			(at -0.2667 0 270)
			(size 0.3048 0.381)
			(layers "F.Cu" "F.Mask" "F.Paste")
			(net "P5E_CPU0_P3_TX_C_DP<2>")
		)
		(pad "2" smd rect
			(at 0.2667 0 270)
			(size 0.3048 0.381)
			(layers "F.Cu" "F.Mask" "F.Paste")
			(net "P5E_CPU0_P3_TX_DP<2>")
		)
	)
	(footprint ""
		(layer "F.Cu")
		(at 326.81926 -325.656448)
		(property "Reference" "PL11"
			(at 0.313944 -15.887446 0)
			(unlocked yes)
			(layer "F.SilkS")
			(effects
				(font
					(size 0.7874 0.5842)
					(thickness 0.1524)
				)
				(justify left)
			)
		)
		(property "Value" ""
			(at 0 0 0)
			(layer "F.Fab")
			(effects
				(font
					(size 1.27 1.27)
				)
			)
		)
		(duplicate_pad_numbers_are_jumpers no)
		(fp_line
			(start -3.750056 -5.500116)
			(end -2.393442 -5.500116)
			(stroke
				(width 0.1524)
				(type default)
			)
			(layer "F.SilkS")
		)
		(fp_line
			(start -3.750056 5.500116)
			(end -3.750056 -5.500116)
			(stroke
				(width 0.1524)
				(type default)
			)
			(layer "F.SilkS")
		)
		(fp_line
			(start -2.393442 5.500116)
			(end -3.750056 5.500116)
			(stroke
				(width 0.1524)
				(type default)
			)
			(layer "F.SilkS")
		)
		(fp_line
			(start 2.393442 5.500116)
			(end 3.750056 5.500116)
			(stroke
				(width 0.1524)
				(type default)
			)
			(layer "F.SilkS")
		)
		(fp_line
			(start 3.750056 -5.500116)
			(end 2.393442 -5.500116)
			(stroke
				(width 0.1524)
				(type default)
			)
			(layer "F.SilkS")
		)
		(fp_line
			(start 3.750056 5.500116)
			(end 3.750056 -5.500116)
			(stroke
				(width 0.1524)
				(type default)
			)
			(layer "F.SilkS")
		)
		(fp_poly
			(pts
				(xy -3.9116 -4.249928) (xy -4.3434 -4.034028) (xy -4.3434 -4.465828)
			)
			(stroke
				(width 0)
				(type default)
			)
			(fill yes)
			(layer "F.SilkS")
		)
		(fp_line
			(start -3.750056 -5.500116)
			(end -3.750056 5.500116)
			(stroke
				(width 0.1)
				(type default)
			)
			(layer "F.Fab")
		)
		(fp_line
			(start -3.750056 5.500116)
			(end 3.750056 5.500116)
			(stroke
				(width 0.1)
				(type default)
			)
			(layer "F.Fab")
		)
		(fp_line
			(start 3.750056 -5.500116)
			(end -3.750056 -5.500116)
			(stroke
				(width 0.1)
				(type default)
			)
			(layer "F.Fab")
		)
		(fp_line
			(start 3.750056 5.500116)
			(end 3.750056 -5.500116)
			(stroke
				(width 0.1)
				(type default)
			)
			(layer "F.Fab")
		)
		(fp_poly
			(pts
				(xy -4.9276 -4.757928) (xy -4.9276 -3.741928) (xy -3.9116 -4.249928)
			)
			(stroke
				(width 0)
				(type default)
			)
			(fill yes)
			(layer "F.Fab")
		)
		(pad "1" smd rect
			(at 0 -4.249928 270)
			(size 2.413 4.5212)
			(layers "F.Cu" "F.Mask" "F.Paste")
			(net "SW_PVDDCR_CPU1_P0_SW2")
		)
		(pad "2" smd rect
			(at 0 -1.175004 270)
			(size 1.3716 4.5212)
			(layers "F.Cu" "F.Mask" "F.Paste")
			(net "IND_CPU1_P0_CPL1")
		)
		(pad "3" smd rect
			(at 0 1.175004 270)
			(size 1.3716 4.5212)
			(layers "F.Cu" "F.Mask" "F.Paste")
			(net "IND_CPU1_P0_CPL2")
		)
		(pad "4" smd rect
			(at 0 4.249928 270)
			(size 2.413 4.5212)
			(layers "F.Cu" "F.Mask" "F.Paste")
			(net "PVDDCR_CPU1_P0")
		)
	)
)
